(kicad_pcb
	(version 20260206)
	(generator "pcbnew")
	(generator_version "10.0")
	(general
		(thickness 1.6)
		(legacy_teardrops no)
	)
	(paper "A4")
	(title_block
		(title "Bryce Canyon_IOM_M2_16342-2_OCP.brd")
		(comment 1 "Bryce Canyon / footprint 577 of 1146 (CN1), pads 149-202 of 202")
	)
	(layers
		(0 "F.Cu" signal "TOP")
		(4 "In1.Cu" signal "L2GND")
		(6 "In2.Cu" signal "L3")
		(8 "In3.Cu" signal "L4VCC")
		(10 "In4.Cu" signal "L5VCC")
		(12 "In5.Cu" signal "L6")
		(14 "In6.Cu" signal "L7GND")
		(2 "B.Cu" signal "BOTTOM")
		(9 "F.Adhes" user "F.Adhesive")
		(11 "B.Adhes" user "B.Adhesive")
		(13 "F.Paste" user "Package Geometry/Pastemask Top")
		(15 "B.Paste" user "Package Geometry/Pastemask Bottom")
		(5 "F.SilkS" user "Ref Des/Silkscreen Top")
		(7 "B.SilkS" user "Ref Des/Silkscreen Bottom")
		(1 "F.Mask" user "Board Geometry/Soldermask Top")
		(3 "B.Mask" user "Board Geometry/Soldermask Bottom")
		(17 "Dwgs.User" user "User.Drawings")
		(19 "Cmts.User" user "User.Comments")
		(21 "Eco1.User" user "User.Eco1")
		(23 "Eco2.User" user "User.Eco2")
		(25 "Edge.Cuts" user "Board Geometry/Outline")
		(27 "Margin" user)
		(31 "F.CrtYd" user "Package Geometry/Place Bound Top")
		(29 "B.CrtYd" user "Package Geometry/Place Bound Bottom")
		(35 "F.Fab" user "Ref Des/Assembly Top")
		(33 "B.Fab" user "Ref Des/Assembly Bottom")
	)
	(footprint ""
		(layer "F.Cu")
		(at 141.299946 -44.200064 180)
		(property "Reference" "CN1"
			(at 0 0 180)
			(layer "F.SilkS")
			(hide yes)
			(effects
				(font
					(size 1.27 1.27)
				)
			)
		)
		(property "Value" "AMP-CONN200-13R-4-GP"
			(at 30.332934 43.515534 180)
			(unlocked yes)
			(layer "F.Fab")
			(hide yes)
			(effects
				(font
					(size 1.016 1.016)
					(thickness 0.1524)
				)
			)
		)
		(property "Device Type" "PREFIT-200P-360520-1H542"
			(at 30.332934 41.991534 180)
			(unlocked yes)
			(layer "F.Fab")
			(hide yes)
			(effects
				(font
					(size 1.016 1.016)
					(thickness 0.1524)
				)
			)
		)
		(duplicate_pad_numbers_are_jumpers no)
		(pad "GND35" thru_hole circle
			(at 12.599924 -8.50011 180)
			(size 0.762 0.762)
			(drill 0.359918)
			(layers "*.Cu" "*.Mask")
			(remove_unused_layers no)
			(net "GND")
			(clearance 0.1651)
			(thermal_gap 0.1651)
		)
		(pad "GND36" thru_hole circle
			(at 12.599924 -12.100052 180)
			(size 0.762 0.762)
			(drill 0.359918)
			(layers "*.Cu" "*.Mask")
			(remove_unused_layers no)
			(net "GND")
			(clearance 0.1651)
			(thermal_gap 0.1651)
		)
		(pad "GND37" thru_hole circle
			(at 21.599906 -2.500122 180)
			(size 0.762 0.762)
			(drill 0.359918)
			(layers "*.Cu" "*.Mask")
			(remove_unused_layers no)
			(net "GND")
			(clearance 0.1651)
			(thermal_gap 0.1651)
		)
		(pad "GND38" thru_hole circle
			(at 21.599906 -6.100064 180)
			(size 0.762 0.762)
			(drill 0.359918)
			(layers "*.Cu" "*.Mask")
			(remove_unused_layers no)
			(net "GND")
			(clearance 0.1651)
			(thermal_gap 0.1651)
		)
		(pad "GND39" thru_hole circle
			(at 21.599906 -9.700006 180)
			(size 0.762 0.762)
			(drill 0.359918)
			(layers "*.Cu" "*.Mask")
			(remove_unused_layers no)
			(net "GND")
			(clearance 0.1651)
			(thermal_gap 0.1651)
		)
		(pad "GND40" thru_hole circle
			(at 21.599906 -13.299948 180)
			(size 0.762 0.762)
			(drill 0.359918)
			(layers "*.Cu" "*.Mask")
			(remove_unused_layers no)
			(net "GND")
			(clearance 0.1651)
			(thermal_gap 0.1651)
		)
		(pad "GND41" thru_hole circle
			(at 23.400004 2.29997 180)
			(size 0.762 0.762)
			(drill 0.359918)
			(layers "*.Cu" "*.Mask")
			(remove_unused_layers no)
			(net "GND")
			(clearance 0.1651)
			(thermal_gap 0.1651)
		)
		(pad "GND42" thru_hole circle
			(at 23.400004 -1.299972 180)
			(size 0.762 0.762)
			(drill 0.359918)
			(layers "*.Cu" "*.Mask")
			(remove_unused_layers no)
			(net "GND")
			(clearance 0.1651)
			(thermal_gap 0.1651)
		)
		(pad "GND43" thru_hole circle
			(at 23.400004 -4.899914 180)
			(size 0.762 0.762)
			(drill 0.359918)
			(layers "*.Cu" "*.Mask")
			(remove_unused_layers no)
			(net "GND")
			(clearance 0.1651)
			(thermal_gap 0.1651)
		)
		(pad "GND44" thru_hole circle
			(at 23.400004 -8.50011 180)
			(size 0.762 0.762)
			(drill 0.359918)
			(layers "*.Cu" "*.Mask")
			(remove_unused_layers no)
			(net "GND")
			(clearance 0.1651)
			(thermal_gap 0.1651)
		)
		(pad "GND45" thru_hole circle
			(at 23.400004 -12.100052 180)
			(size 0.762 0.762)
			(drill 0.359918)
			(layers "*.Cu" "*.Mask")
			(remove_unused_layers no)
			(net "GND")
			(clearance 0.1651)
			(thermal_gap 0.1651)
		)
		(pad "GND46" thru_hole circle
			(at 25.200102 -2.500122 180)
			(size 0.762 0.762)
			(drill 0.359918)
			(layers "*.Cu" "*.Mask")
			(remove_unused_layers no)
			(net "GND")
			(clearance 0.1651)
			(thermal_gap 0.1651)
		)
		(pad "GND47" thru_hole circle
			(at 25.200102 -6.100064 180)
			(size 0.762 0.762)
			(drill 0.359918)
			(layers "*.Cu" "*.Mask")
			(remove_unused_layers no)
			(net "GND")
			(clearance 0.1651)
			(thermal_gap 0.1651)
		)
		(pad "GND48" thru_hole circle
			(at 25.200102 -9.700006 180)
			(size 0.762 0.762)
			(drill 0.359918)
			(layers "*.Cu" "*.Mask")
			(remove_unused_layers no)
			(net "GND")
			(clearance 0.1651)
			(thermal_gap 0.1651)
		)
		(pad "GND49" thru_hole circle
			(at 25.200102 -13.299948 180)
			(size 0.762 0.762)
			(drill 0.359918)
			(layers "*.Cu" "*.Mask")
			(remove_unused_layers no)
			(net "GND")
			(clearance 0.1651)
			(thermal_gap 0.1651)
		)
		(pad "GND50" thru_hole circle
			(at 26.999946 2.29997 180)
			(size 0.762 0.762)
			(drill 0.359918)
			(layers "*.Cu" "*.Mask")
			(remove_unused_layers no)
			(net "GND")
			(clearance 0.1651)
			(thermal_gap 0.1651)
		)
		(pad "GND51" thru_hole circle
			(at 26.999946 -1.299972 180)
			(size 0.762 0.762)
			(drill 0.359918)
			(layers "*.Cu" "*.Mask")
			(remove_unused_layers no)
			(net "GND")
			(clearance 0.1651)
			(thermal_gap 0.1651)
		)
		(pad "GND52" thru_hole circle
			(at 26.999946 -4.899914 180)
			(size 0.762 0.762)
			(drill 0.359918)
			(layers "*.Cu" "*.Mask")
			(remove_unused_layers no)
			(net "GND")
			(clearance 0.1651)
			(thermal_gap 0.1651)
		)
		(pad "GND53" thru_hole circle
			(at 26.999946 -8.50011 180)
			(size 0.762 0.762)
			(drill 0.359918)
			(layers "*.Cu" "*.Mask")
			(remove_unused_layers no)
			(net "GND")
			(clearance 0.1651)
			(thermal_gap 0.1651)
		)
		(pad "GND54" thru_hole circle
			(at 26.999946 -12.100052 180)
			(size 0.762 0.762)
			(drill 0.359918)
			(layers "*.Cu" "*.Mask")
			(remove_unused_layers no)
			(net "GND")
			(clearance 0.1651)
			(thermal_gap 0.1651)
		)
		(pad "GND55" thru_hole circle
			(at 28.800044 -2.500122 180)
			(size 0.762 0.762)
			(drill 0.359918)
			(layers "*.Cu" "*.Mask")
			(remove_unused_layers no)
			(net "GND")
			(clearance 0.1651)
			(thermal_gap 0.1651)
		)
		(pad "GND56" thru_hole circle
			(at 28.800044 -6.100064 180)
			(size 0.762 0.762)
			(drill 0.359918)
			(layers "*.Cu" "*.Mask")
			(remove_unused_layers no)
			(net "GND")
			(clearance 0.1651)
			(thermal_gap 0.1651)
		)
		(pad "GND57" thru_hole circle
			(at 28.800044 -9.700006 180)
			(size 0.762 0.762)
			(drill 0.359918)
			(layers "*.Cu" "*.Mask")
			(remove_unused_layers no)
			(net "GND")
			(clearance 0.1651)
			(thermal_gap 0.1651)
		)
		(pad "GND58" thru_hole circle
			(at 28.800044 -13.299948 180)
			(size 0.762 0.762)
			(drill 0.359918)
			(layers "*.Cu" "*.Mask")
			(remove_unused_layers no)
			(net "GND")
			(clearance 0.1651)
			(thermal_gap 0.1651)
		)
		(pad "GND59" thru_hole circle
			(at 30.599888 2.29997 180)
			(size 0.762 0.762)
			(drill 0.359918)
			(layers "*.Cu" "*.Mask")
			(remove_unused_layers no)
			(net "GND")
			(clearance 0.1651)
			(thermal_gap 0.1651)
		)
		(pad "GND60" thru_hole circle
			(at 30.599888 -1.299972 180)
			(size 0.762 0.762)
			(drill 0.359918)
			(layers "*.Cu" "*.Mask")
			(remove_unused_layers no)
			(net "GND")
			(clearance 0.1651)
			(thermal_gap 0.1651)
		)
		(pad "GND61" thru_hole circle
			(at 30.599888 -4.899914 180)
			(size 0.762 0.762)
			(drill 0.359918)
			(layers "*.Cu" "*.Mask")
			(remove_unused_layers no)
			(net "GND")
			(clearance 0.1651)
			(thermal_gap 0.1651)
		)
		(pad "GND62" thru_hole circle
			(at 30.599888 -8.50011 180)
			(size 0.762 0.762)
			(drill 0.359918)
			(layers "*.Cu" "*.Mask")
			(remove_unused_layers no)
			(net "GND")
			(clearance 0.1651)
			(thermal_gap 0.1651)
		)
		(pad "GND63" thru_hole circle
			(at 30.599888 -12.100052 180)
			(size 0.762 0.762)
			(drill 0.359918)
			(layers "*.Cu" "*.Mask")
			(remove_unused_layers no)
			(net "GND")
			(clearance 0.1651)
			(thermal_gap 0.1651)
		)
		(pad "GND64" thru_hole circle
			(at 32.399986 -2.500122 180)
			(size 0.762 0.762)
			(drill 0.359918)
			(layers "*.Cu" "*.Mask")
			(remove_unused_layers no)
			(net "GND")
			(clearance 0.1651)
			(thermal_gap 0.1651)
		)
		(pad "GND65" thru_hole circle
			(at 32.399986 -6.100064 180)
			(size 0.762 0.762)
			(drill 0.359918)
			(layers "*.Cu" "*.Mask")
			(remove_unused_layers no)
			(net "GND")
			(clearance 0.1651)
			(thermal_gap 0.1651)
		)
		(pad "GND66" thru_hole circle
			(at 32.399986 -9.700006 180)
			(size 0.762 0.762)
			(drill 0.359918)
			(layers "*.Cu" "*.Mask")
			(remove_unused_layers no)
			(net "GND")
			(clearance 0.1651)
			(thermal_gap 0.1651)
		)
		(pad "GND67" thru_hole circle
			(at 32.399986 -13.299948 180)
			(size 0.762 0.762)
			(drill 0.359918)
			(layers "*.Cu" "*.Mask")
			(remove_unused_layers no)
			(net "GND")
			(clearance 0.1651)
			(thermal_gap 0.1651)
		)
		(pad "GND68" thru_hole circle
			(at 34.200084 2.29997 180)
			(size 0.762 0.762)
			(drill 0.359918)
			(layers "*.Cu" "*.Mask")
			(remove_unused_layers no)
			(net "GND")
			(clearance 0.1651)
			(thermal_gap 0.1651)
		)
		(pad "GND69" thru_hole circle
			(at 34.200084 -1.299972 180)
			(size 0.762 0.762)
			(drill 0.359918)
			(layers "*.Cu" "*.Mask")
			(remove_unused_layers no)
			(net "GND")
			(clearance 0.1651)
			(thermal_gap 0.1651)
		)
		(pad "GND70" thru_hole circle
			(at 34.200084 -4.899914 180)
			(size 0.762 0.762)
			(drill 0.359918)
			(layers "*.Cu" "*.Mask")
			(remove_unused_layers no)
			(net "GND")
			(clearance 0.1651)
			(thermal_gap 0.1651)
		)
		(pad "GND71" thru_hole circle
			(at 34.200084 -8.50011 180)
			(size 0.762 0.762)
			(drill 0.359918)
			(layers "*.Cu" "*.Mask")
			(remove_unused_layers no)
			(net "GND")
			(clearance 0.1651)
			(thermal_gap 0.1651)
		)
		(pad "GND72" thru_hole circle
			(at 34.200084 -12.100052 180)
			(size 0.762 0.762)
			(drill 0.359918)
			(layers "*.Cu" "*.Mask")
			(remove_unused_layers no)
			(net "GND")
			(clearance 0.1651)
			(thermal_gap 0.1651)
		)
		(pad "H1" thru_hole circle
			(at 0 -12.199874 180)
			(size 0.762 0.762)
			(drill 0.359918)
			(layers "*.Cu" "*.Mask")
			(remove_unused_layers no)
			(net "PCIE_COMP_TO_IOM_8_DP")
			(clearance 0.1651)
			(thermal_gap 0.1651)
		)
		(pad "H2" thru_hole circle
			(at 1.800098 -10.999978 180)
			(size 0.762 0.762)
			(drill 0.359918)
			(layers "*.Cu" "*.Mask")
			(remove_unused_layers no)
			(net "PCIE_COMP_TO_IOM_9_DP")
			(clearance 0.1651)
			(thermal_gap 0.1651)
		)
		(pad "H3" thru_hole circle
			(at 3.599942 -12.199874 180)
			(size 0.762 0.762)
			(drill 0.359918)
			(layers "*.Cu" "*.Mask")
			(remove_unused_layers no)
			(net "PCIE_COMP_TO_IOM_10_DP")
			(clearance 0.1651)
			(thermal_gap 0.1651)
		)
		(pad "H4" thru_hole circle
			(at 5.40004 -10.999978 180)
			(size 0.762 0.762)
			(drill 0.359918)
			(layers "*.Cu" "*.Mask")
			(remove_unused_layers no)
			(net "PCIE_COMP_TO_IOM_11_DP")
			(clearance 0.1651)
			(thermal_gap 0.1651)
		)
		(pad "H5" thru_hole circle
			(at 7.199884 -12.199874 180)
			(size 0.762 0.762)
			(drill 0.359918)
			(layers "*.Cu" "*.Mask")
			(remove_unused_layers no)
			(net "PCIE_COMP_TO_IOM_12_DP")
			(clearance 0.1651)
			(thermal_gap 0.1651)
		)
		(pad "H6" thru_hole circle
			(at 8.999982 -10.999978 180)
			(size 0.762 0.762)
			(drill 0.359918)
			(layers "*.Cu" "*.Mask")
			(remove_unused_layers no)
			(net "PCIE_COMP_TO_IOM_13_DP")
			(clearance 0.1651)
			(thermal_gap 0.1651)
		)
		(pad "H7" thru_hole circle
			(at 10.80008 -12.199874 180)
			(size 0.762 0.762)
			(drill 0.359918)
			(layers "*.Cu" "*.Mask")
			(remove_unused_layers no)
			(net "PCIE_COMP_TO_IOM_14_DP")
			(clearance 0.1651)
			(thermal_gap 0.1651)
		)
		(pad "H8" thru_hole circle
			(at 12.599924 -10.999978 180)
			(size 0.762 0.762)
			(drill 0.359918)
			(layers "*.Cu" "*.Mask")
			(remove_unused_layers no)
			(net "PCIE_COMP_TO_IOM_15_DP")
			(clearance 0.1651)
			(thermal_gap 0.1651)
		)
		(pad "H9" thru_hole circle
			(at 21.599906 -12.199874 180)
			(size 0.762 0.762)
			(drill 0.359918)
			(layers "*.Cu" "*.Mask")
			(remove_unused_layers no)
			(net "PCIE_COMP_TO_IOM_16_DP")
			(clearance 0.1651)
			(thermal_gap 0.1651)
		)
		(pad "H10" thru_hole circle
			(at 23.400004 -10.999978 180)
			(size 0.762 0.762)
			(drill 0.359918)
			(layers "*.Cu" "*.Mask")
			(remove_unused_layers no)
			(net "PCIE_COMP_TO_IOM_17_DP")
			(clearance 0.1651)
			(thermal_gap 0.1651)
		)
		(pad "H11" thru_hole circle
			(at 25.200102 -12.199874 180)
			(size 0.762 0.762)
			(drill 0.359918)
			(layers "*.Cu" "*.Mask")
			(remove_unused_layers no)
			(net "PCIE_COMP_TO_IOM_18_DP")
			(clearance 0.1651)
			(thermal_gap 0.1651)
		)
		(pad "H12" thru_hole circle
			(at 26.999946 -10.999978 180)
			(size 0.762 0.762)
			(drill 0.359918)
			(layers "*.Cu" "*.Mask")
			(remove_unused_layers no)
			(net "PCIE_COMP_TO_IOM_19_DP")
			(clearance 0.1651)
			(thermal_gap 0.1651)
		)
		(pad "H13" thru_hole circle
			(at 28.800044 -12.199874 180)
			(size 0.762 0.762)
			(drill 0.359918)
			(layers "*.Cu" "*.Mask")
			(remove_unused_layers no)
			(net "PCIE_COMP_TO_IOM_20_DP")
			(clearance 0.1651)
			(thermal_gap 0.1651)
		)
		(pad "H14" thru_hole circle
			(at 30.599888 -10.999978 180)
			(size 0.762 0.762)
			(drill 0.359918)
			(layers "*.Cu" "*.Mask")
			(remove_unused_layers no)
			(net "PCIE_COMP_TO_IOM_21_DP")
			(clearance 0.1651)
			(thermal_gap 0.1651)
		)
		(pad "H15" thru_hole circle
			(at 32.399986 -12.199874 180)
			(size 0.762 0.762)
			(drill 0.359918)
			(layers "*.Cu" "*.Mask")
			(remove_unused_layers no)
			(net "PCIE_COMP_TO_IOM_22_DP")
			(clearance 0.1651)
			(thermal_gap 0.1651)
		)
		(pad "H16" thru_hole circle
			(at 34.200084 -10.999978 180)
			(size 0.762 0.762)
			(drill 0.359918)
			(layers "*.Cu" "*.Mask")
			(remove_unused_layers no)
			(net "PCIE_COMP_TO_IOM_23_DP")
			(clearance 0.1651)
			(thermal_gap 0.1651)
		)
	)
)
